(kicad_pcb
	(version 20260206)
	(generator "pcbnew")
	(generator_version "10.0")
	(general
		(thickness 1.6)
		(legacy_teardrops no)
	)
	(paper "A4")
	(title_block
		(title "baseboard — 13948-1b.1110WZS1818.brd")
		(comment 1 "Honey Badger (Wiwynn) / footprints 1205-1212 of 2523")
	)
	(layers
		(0 "F.Cu" signal "TOP")
		(4 "In1.Cu" signal "L2GND")
		(6 "In2.Cu" signal "L3")
		(8 "In3.Cu" signal "L4VCC")
		(10 "In4.Cu" signal "L5VCC")
		(12 "In5.Cu" signal "L6")
		(14 "In6.Cu" signal "L7GND")
		(2 "B.Cu" signal "BOTTOM")
		(9 "F.Adhes" user "F.Adhesive")
		(11 "B.Adhes" user "B.Adhesive")
		(13 "F.Paste" user "Package Geometry/Pastemask Top")
		(15 "B.Paste" user "Package Geometry/Pastemask Bottom")
		(5 "F.SilkS" user "Ref Des/Silkscreen Top")
		(7 "B.SilkS" user "Ref Des/Silkscreen Bottom")
		(1 "F.Mask" user "Board Geometry/Soldermask Top")
		(3 "B.Mask" user "Board Geometry/Soldermask Bottom")
		(17 "Dwgs.User" user "User.Drawings")
		(19 "Cmts.User" user "User.Comments")
		(21 "Eco1.User" user "User.Eco1")
		(23 "Eco2.User" user "User.Eco2")
		(25 "Edge.Cuts" user "Board Geometry/Outline")
		(27 "Margin" user)
		(31 "F.CrtYd" user "Package Geometry/Place Bound Top")
		(29 "B.CrtYd" user "Package Geometry/Place Bound Bottom")
		(35 "F.Fab" user "Ref Des/Assembly Top")
		(33 "B.Fab" user "Ref Des/Assembly Bottom")
	)
	(footprint ""
		(layer "F.Cu")
		(at 268.351 -220.091 90)
		(property "Reference" "PC95"
			(at 0 0 90)
			(layer "F.SilkS")
			(hide yes)
			(effects
				(font
					(size 1.27 1.27)
				)
			)
		)
		(property "Value" "SC10U6D3V5KX-1GP"
			(at -0.0762 -6.1214 90)
			(unlocked yes)
			(layer "F.Fab")
			(hide yes)
			(effects
				(font
					(size 1.016 1.016)
					(thickness 0.1524)
				)
			)
		)
		(property "Device Type" "C805H54"
			(at -0.0762 -8.1534 90)
			(unlocked yes)
			(layer "F.Fab")
			(hide yes)
			(effects
				(font
					(size 1.016 1.016)
					(thickness 0.1524)
				)
			)
		)
		(duplicate_pad_numbers_are_jumpers no)
		(fp_line
			(start 0.635 0)
			(end -0.635 0)
			(stroke
				(width 0.508)
				(type default)
			)
			(layer "F.SilkS")
		)
		(fp_rect
			(start -0.9652 1.778)
			(end 0.9652 -1.778)
			(stroke
				(width 0)
				(type default)
			)
			(fill no)
			(layer "F.CrtYd")
		)
		(fp_poly
			(pts
				(xy -0.9652 -1.778) (xy 0.9652 -1.778) (xy 0.9652 1.778) (xy -0.9652 1.778)
			)
			(stroke
				(width 0)
				(type default)
			)
			(fill no)
			(layer "F.Fab")
		)
		(pad "1" smd rect
			(at 0 -0.9652 90)
			(size 1.397 1.143)
			(layers "F.Cu" "F.Mask" "F.Paste")
			(net "TPS74801_1V26_STBY_OUT")
		)
		(pad "2" smd rect
			(at 0 0.9652 90)
			(size 1.397 1.143)
			(layers "F.Cu" "F.Mask" "F.Paste")
			(net "GND")
		)
	)
	(footprint ""
		(layer "F.Cu")
		(at 49.403 -219.202)
		(property "Reference" "R2174"
			(at 0 0 0)
			(layer "F.SilkS")
			(hide yes)
			(effects
				(font
					(size 1.27 1.27)
				)
			)
		)
		(property "Value" "100KR2J-4-GP"
			(at -1.1811 -1.1303 0)
			(unlocked yes)
			(layer "F.Fab")
			(hide yes)
			(effects
				(font
					(size 1.016 1.016)
					(thickness 0.1524)
				)
			)
		)
		(property "Device Type" "R402H15"
			(at -1.1811 -2.6543 0)
			(unlocked yes)
			(layer "F.Fab")
			(hide yes)
			(effects
				(font
					(size 1.016 1.016)
					(thickness 0.1524)
				)
			)
		)
		(duplicate_pad_numbers_are_jumpers no)
		(fp_line
			(start -0.508 -0.9398)
			(end -0.508 0.9398)
			(stroke
				(width 0.1524)
				(type default)
			)
			(layer "F.SilkS")
		)
		(fp_line
			(start 0.508 -0.9398)
			(end -0.508 -0.9398)
			(stroke
				(width 0.1524)
				(type default)
			)
			(layer "F.SilkS")
		)
		(fp_rect
			(start -0.508 0.9398)
			(end 0.508 -0.9398)
			(stroke
				(width 0)
				(type default)
			)
			(fill no)
			(layer "F.CrtYd")
		)
		(fp_rect
			(start -0.508 0.9398)
			(end 0.508 -0.9398)
			(stroke
				(width 0)
				(type default)
			)
			(fill no)
			(layer "F.Fab")
		)
		(pad "1" smd custom
			(at 0 -0.4445)
			(size 0.1397 0.1397)
			(layers "F.Cu" "F.Mask" "F.Paste")
			(net "MB0_VCAP_R")
			(options
				(clearance outline)
				(anchor circle)
			)
			(primitives
				(gr_poly
					(pts
						(arc
							(start -0.1778 -0.2794)
							(mid -0.249642 -0.249642)
							(end -0.2794 -0.1778)
						)
						(arc
							(start -0.2794 0.1778)
							(mid -0.249642 0.249642)
							(end -0.1778 0.2794)
						)
						(arc
							(start 0.1778 0.2794)
							(mid 0.249642 0.249642)
							(end 0.2794 0.1778)
						)
						(arc
							(start 0.2794 -0.1778)
							(mid 0.249642 -0.249642)
							(end 0.1778 -0.2794)
						)
					)
					(width 0)
					(fill yes)
				)
			)
		)
		(pad "2" smd custom
			(at 0 0.4445)
			(size 0.1397 0.1397)
			(layers "F.Cu" "F.Mask" "F.Paste")
			(net "MB0_ISTART_R")
			(options
				(clearance outline)
				(anchor circle)
			)
			(primitives
				(gr_poly
					(pts
						(arc
							(start -0.1778 -0.2794)
							(mid -0.249642 -0.249642)
							(end -0.2794 -0.1778)
						)
						(arc
							(start -0.2794 0.1778)
							(mid -0.249642 0.249642)
							(end -0.1778 0.2794)
						)
						(arc
							(start 0.1778 0.2794)
							(mid 0.249642 0.249642)
							(end 0.2794 0.1778)
						)
						(arc
							(start 0.2794 -0.1778)
							(mid 0.249642 -0.249642)
							(end 0.1778 -0.2794)
						)
					)
					(width 0)
					(fill yes)
				)
			)
		)
	)
	(footprint ""
		(layer "F.Cu")
		(at 318.893952 -57.404 -90)
		(property "Reference" "R211"
			(at 0 0 270)
			(layer "F.SilkS")
			(hide yes)
			(effects
				(font
					(size 1.27 1.27)
				)
			)
		)
		(property "Value" "0R2J-2-GP"
			(at 0.064008 -3.993896 270)
			(unlocked yes)
			(layer "F.Fab")
			(hide yes)
			(effects
				(font
					(size 1.016 1.016)
					(thickness 0.1524)
				)
			)
		)
		(property "Device Type" "R402H16"
			(at 0.064008 -5.517896 270)
			(unlocked yes)
			(layer "F.Fab")
			(hide yes)
			(effects
				(font
					(size 1.016 1.016)
					(thickness 0.1524)
				)
			)
		)
		(duplicate_pad_numbers_are_jumpers no)
		(fp_line
			(start -0.508 -0.9398)
			(end -0.508 0.9398)
			(stroke
				(width 0.1524)
				(type default)
			)
			(layer "F.SilkS")
		)
		(fp_line
			(start 0.508 -0.9398)
			(end -0.508 -0.9398)
			(stroke
				(width 0.1524)
				(type default)
			)
			(layer "F.SilkS")
		)
		(fp_rect
			(start -0.508 0.9398)
			(end 0.508 -0.9398)
			(stroke
				(width 0)
				(type default)
			)
			(fill no)
			(layer "F.CrtYd")
		)
		(fp_rect
			(start -0.508 0.9398)
			(end 0.508 -0.9398)
			(stroke
				(width 0)
				(type default)
			)
			(fill no)
			(layer "F.Fab")
		)
		(pad "1" smd custom
			(at 0 -0.4445 270)
			(size 0.1397 0.1397)
			(layers "F.Cu" "F.Mask" "F.Paste")
			(net "NCSI_10G_RCLK")
			(options
				(clearance outline)
				(anchor circle)
			)
			(primitives
				(gr_poly
					(pts
						(arc
							(start -0.1778 -0.2794)
							(mid -0.249642 -0.249642)
							(end -0.2794 -0.1778)
						)
						(arc
							(start -0.2794 0.1778)
							(mid -0.249642 0.249642)
							(end -0.1778 0.2794)
						)
						(arc
							(start 0.1778 0.2794)
							(mid 0.249642 0.249642)
							(end 0.2794 0.1778)
						)
						(arc
							(start 0.2794 -0.1778)
							(mid 0.249642 -0.249642)
							(end 0.1778 -0.2794)
						)
					)
					(width 0)
					(fill yes)
				)
			)
		)
		(pad "2" smd custom
			(at 0 0.4445 270)
			(size 0.1397 0.1397)
			(layers "F.Cu" "F.Mask" "F.Paste")
			(net "NCSI_10G_RCLK_R")
			(options
				(clearance outline)
				(anchor circle)
			)
			(primitives
				(gr_poly
					(pts
						(arc
							(start -0.1778 -0.2794)
							(mid -0.249642 -0.249642)
							(end -0.2794 -0.1778)
						)
						(arc
							(start -0.2794 0.1778)
							(mid -0.249642 0.249642)
							(end -0.1778 0.2794)
						)
						(arc
							(start 0.1778 0.2794)
							(mid 0.249642 0.249642)
							(end 0.2794 0.1778)
						)
						(arc
							(start 0.2794 -0.1778)
							(mid 0.249642 -0.249642)
							(end 0.1778 -0.2794)
						)
					)
					(width 0)
					(fill yes)
				)
			)
		)
	)
	(footprint ""
		(layer "F.Cu")
		(at 121.990612 -222.885)
		(property "Reference" "SR869"
			(at 0 0 0)
			(layer "F.SilkS")
			(hide yes)
			(effects
				(font
					(size 1.27 1.27)
				)
			)
		)
		(property "Value" "0R2J-2-GP"
			(at 0.064008 -3.993896 0)
			(unlocked yes)
			(layer "F.Fab")
			(hide yes)
			(effects
				(font
					(size 1.016 1.016)
					(thickness 0.1524)
				)
			)
		)
		(property "Device Type" "R402H16"
			(at 0.064008 -5.517896 0)
			(unlocked yes)
			(layer "F.Fab")
			(hide yes)
			(effects
				(font
					(size 1.016 1.016)
					(thickness 0.1524)
				)
			)
		)
		(duplicate_pad_numbers_are_jumpers no)
		(fp_line
			(start -0.508 -0.9398)
			(end -0.508 0.9398)
			(stroke
				(width 0.1524)
				(type default)
			)
			(layer "F.SilkS")
		)
		(fp_line
			(start 0.508 -0.9398)
			(end -0.508 -0.9398)
			(stroke
				(width 0.1524)
				(type default)
			)
			(layer "F.SilkS")
		)
		(fp_rect
			(start -0.508 0.9398)
			(end 0.508 -0.9398)
			(stroke
				(width 0)
				(type default)
			)
			(fill no)
			(layer "F.CrtYd")
		)
		(fp_rect
			(start -0.508 0.9398)
			(end 0.508 -0.9398)
			(stroke
				(width 0)
				(type default)
			)
			(fill no)
			(layer "F.Fab")
		)
		(pad "1" smd custom
			(at 0 -0.4445)
			(size 0.1397 0.1397)
			(layers "F.Cu" "F.Mask" "F.Paste")
			(net "SAS_HDD_CONN_SER_TX7_P")
			(options
				(clearance outline)
				(anchor circle)
			)
			(primitives
				(gr_poly
					(pts
						(arc
							(start -0.1778 -0.2794)
							(mid -0.249642 -0.249642)
							(end -0.2794 -0.1778)
						)
						(arc
							(start -0.2794 0.1778)
							(mid -0.249642 0.249642)
							(end -0.1778 0.2794)
						)
						(arc
							(start 0.1778 0.2794)
							(mid 0.249642 0.249642)
							(end 0.2794 0.1778)
						)
						(arc
							(start 0.2794 -0.1778)
							(mid 0.249642 -0.249642)
							(end 0.1778 -0.2794)
						)
					)
					(width 0)
					(fill yes)
				)
			)
		)
		(pad "2" smd custom
			(at 0 0.4445)
			(size 0.1397 0.1397)
			(layers "F.Cu" "F.Mask" "F.Paste")
			(net "SAS_HDD_CONN_TX7_P")
			(options
				(clearance outline)
				(anchor circle)
			)
			(primitives
				(gr_poly
					(pts
						(arc
							(start -0.1778 -0.2794)
							(mid -0.249642 -0.249642)
							(end -0.2794 -0.1778)
						)
						(arc
							(start -0.2794 0.1778)
							(mid -0.249642 0.249642)
							(end -0.1778 0.2794)
						)
						(arc
							(start 0.1778 0.2794)
							(mid 0.249642 0.249642)
							(end 0.2794 0.1778)
						)
						(arc
							(start 0.2794 -0.1778)
							(mid 0.249642 -0.249642)
							(end 0.1778 -0.2794)
						)
					)
					(width 0)
					(fill yes)
				)
			)
		)
	)
	(footprint ""
		(layer "F.Cu")
		(at 178.997864 -38.172136)
		(property "Reference" "R378"
			(at 0 0 0)
			(layer "F.SilkS")
			(hide yes)
			(effects
				(font
					(size 1.27 1.27)
				)
			)
		)
		(property "Value" "150R2F-1-GP"
			(at 0.064008 -3.993896 0)
			(unlocked yes)
			(layer "F.Fab")
			(hide yes)
			(effects
				(font
					(size 1.016 1.016)
					(thickness 0.1524)
				)
			)
		)
		(property "Device Type" "R402H16"
			(at 0.064008 -5.517896 0)
			(unlocked yes)
			(layer "F.Fab")
			(hide yes)
			(effects
				(font
					(size 1.016 1.016)
					(thickness 0.1524)
				)
			)
		)
		(duplicate_pad_numbers_are_jumpers no)
		(fp_line
			(start -0.508 -0.9398)
			(end -0.508 0.9398)
			(stroke
				(width 0.1524)
				(type default)
			)
			(layer "F.SilkS")
		)
		(fp_line
			(start 0.508 -0.9398)
			(end -0.508 -0.9398)
			(stroke
				(width 0.1524)
				(type default)
			)
			(layer "F.SilkS")
		)
		(fp_rect
			(start -0.508 0.9398)
			(end 0.508 -0.9398)
			(stroke
				(width 0)
				(type default)
			)
			(fill no)
			(layer "F.CrtYd")
		)
		(fp_rect
			(start -0.508 0.9398)
			(end 0.508 -0.9398)
			(stroke
				(width 0)
				(type default)
			)
			(fill no)
			(layer "F.Fab")
		)
		(pad "1" smd custom
			(at 0 -0.4445)
			(size 0.1397 0.1397)
			(layers "F.Cu" "F.Mask" "F.Paste")
			(net "GND")
			(options
				(clearance outline)
				(anchor circle)
			)
			(primitives
				(gr_poly
					(pts
						(arc
							(start -0.1778 -0.2794)
							(mid -0.249642 -0.249642)
							(end -0.2794 -0.1778)
						)
						(arc
							(start -0.2794 0.1778)
							(mid -0.249642 0.249642)
							(end -0.1778 0.2794)
						)
						(arc
							(start 0.1778 0.2794)
							(mid 0.249642 0.249642)
							(end 0.2794 0.1778)
						)
						(arc
							(start 0.2794 -0.1778)
							(mid 0.249642 -0.249642)
							(end 0.1778 -0.2794)
						)
					)
					(width 0)
					(fill yes)
				)
			)
		)
		(pad "2" smd custom
			(at 0 0.4445)
			(size 0.1397 0.1397)
			(layers "F.Cu" "F.Mask" "F.Paste")
			(net "PHY_TEST_EN")
			(options
				(clearance outline)
				(anchor circle)
			)
			(primitives
				(gr_poly
					(pts
						(arc
							(start -0.1778 -0.2794)
							(mid -0.249642 -0.249642)
							(end -0.2794 -0.1778)
						)
						(arc
							(start -0.2794 0.1778)
							(mid -0.249642 0.249642)
							(end -0.1778 0.2794)
						)
						(arc
							(start 0.1778 0.2794)
							(mid 0.249642 0.249642)
							(end 0.2794 0.1778)
						)
						(arc
							(start 0.2794 -0.1778)
							(mid 0.249642 -0.249642)
							(end 0.1778 -0.2794)
						)
					)
					(width 0)
					(fill yes)
				)
			)
		)
	)
	(footprint ""
		(layer "F.Cu")
		(at 95.89897 -85.09 90)
		(property "Reference" "SR808"
			(at 0 0 90)
			(layer "F.SilkS")
			(hide yes)
			(effects
				(font
					(size 1.27 1.27)
				)
			)
		)
		(property "Value" "4K75R2F-1-GP"
			(at 0.064008 -3.993896 90)
			(unlocked yes)
			(layer "F.Fab")
			(hide yes)
			(effects
				(font
					(size 1.016 1.016)
					(thickness 0.1524)
				)
			)
		)
		(property "Device Type" "R402H16"
			(at 0.064008 -5.517896 90)
			(unlocked yes)
			(layer "F.Fab")
			(hide yes)
			(effects
				(font
					(size 1.016 1.016)
					(thickness 0.1524)
				)
			)
		)
		(duplicate_pad_numbers_are_jumpers no)
		(fp_line
			(start 0.508 -0.9398)
			(end -0.508 -0.9398)
			(stroke
				(width 0.1524)
				(type default)
			)
			(layer "F.SilkS")
		)
		(fp_line
			(start -0.508 -0.9398)
			(end -0.508 0.9398)
			(stroke
				(width 0.1524)
				(type default)
			)
			(layer "F.SilkS")
		)
		(fp_rect
			(start -0.508 0.9398)
			(end 0.508 -0.9398)
			(stroke
				(width 0)
				(type default)
			)
			(fill no)
			(layer "F.CrtYd")
		)
		(fp_rect
			(start -0.508 0.9398)
			(end 0.508 -0.9398)
			(stroke
				(width 0)
				(type default)
			)
			(fill no)
			(layer "F.Fab")
		)
		(pad "1" smd custom
			(at 0 -0.4445 90)
			(size 0.1397 0.1397)
			(layers "F.Cu" "F.Mask" "F.Paste")
			(net "P1V8_E")
			(options
				(clearance outline)
				(anchor circle)
			)
			(primitives
				(gr_poly
					(pts
						(arc
							(start -0.1778 -0.2794)
							(mid -0.249642 -0.249642)
							(end -0.2794 -0.1778)
						)
						(arc
							(start -0.2794 0.1778)
							(mid -0.249642 0.249642)
							(end -0.1778 0.2794)
						)
						(arc
							(start 0.1778 0.2794)
							(mid 0.249642 0.249642)
							(end 0.2794 0.1778)
						)
						(arc
							(start 0.2794 -0.1778)
							(mid 0.249642 -0.249642)
							(end 0.1778 -0.2794)
						)
					)
					(width 0)
					(fill yes)
				)
			)
		)
		(pad "2" smd custom
			(at 0 0.4445 90)
			(size 0.1397 0.1397)
			(layers "F.Cu" "F.Mask" "F.Paste")
			(net "LSI_T_N")
			(options
				(clearance outline)
				(anchor circle)
			)
			(primitives
				(gr_poly
					(pts
						(arc
							(start -0.1778 -0.2794)
							(mid -0.249642 -0.249642)
							(end -0.2794 -0.1778)
						)
						(arc
							(start -0.2794 0.1778)
							(mid -0.249642 0.249642)
							(end -0.1778 0.2794)
						)
						(arc
							(start 0.1778 0.2794)
							(mid 0.249642 0.249642)
							(end 0.2794 0.1778)
						)
						(arc
							(start 0.2794 -0.1778)
							(mid 0.249642 -0.249642)
							(end 0.1778 -0.2794)
						)
					)
					(width 0)
					(fill yes)
				)
			)
		)
	)
	(footprint ""
		(layer "F.Cu")
		(at 90.683842 -123.642882 90)
		(property "Reference" "SC1282"
			(at 0 0 90)
			(layer "F.SilkS")
			(hide yes)
			(effects
				(font
					(size 1.27 1.27)
				)
			)
		)
		(property "Value" "SCD1U16V2KX-3GP"
			(at 1.1811 -2.7051 90)
			(unlocked yes)
			(layer "F.Fab")
			(hide yes)
			(effects
				(font
					(size 1.016 1.016)
					(thickness 0.1524)
				)
			)
		)
		(property "Device Type" "C402H22"
			(at 1.1811 -4.2291 90)
			(unlocked yes)
			(layer "F.Fab")
			(hide yes)
			(effects
				(font
					(size 1.016 1.016)
					(thickness 0.1524)
				)
			)
		)
		(duplicate_pad_numbers_are_jumpers no)
		(fp_rect
			(start -0.4318 0.9525)
			(end 0.4318 -0.9525)
			(stroke
				(width 0)
				(type default)
			)
			(fill no)
			(layer "F.CrtYd")
		)
		(fp_rect
			(start -0.4318 0.9525)
			(end 0.4318 -0.9525)
			(stroke
				(width 0)
				(type default)
			)
			(fill no)
			(layer "F.Fab")
		)
		(pad "1" smd custom
			(at 0 -0.4445 90)
			(size 0.1524 0.1524)
			(layers "F.Cu" "F.Mask" "F.Paste")
			(net "EXP_I2C_VREF_0")
			(options
				(clearance outline)
				(anchor circle)
			)
			(primitives
				(gr_poly
					(pts
						(arc
							(start 0.3048 -0.2032)
							(mid 0.275042 -0.275042)
							(end 0.2032 -0.3048)
						)
						(arc
							(start -0.2032 -0.3048)
							(mid -0.275042 -0.275042)
							(end -0.3048 -0.2032)
						)
						(arc
							(start -0.3048 0.2032)
							(mid -0.275042 0.275042)
							(end -0.2032 0.3048)
						)
						(arc
							(start 0.2032 0.3048)
							(mid 0.275042 0.275042)
							(end 0.3048 0.2032)
						)
					)
					(width 0)
					(fill yes)
				)
			)
		)
		(pad "2" smd custom
			(at 0 0.4445 90)
			(size 0.1524 0.1524)
			(layers "F.Cu" "F.Mask" "F.Paste")
			(net "GND")
			(options
				(clearance outline)
				(anchor circle)
			)
			(primitives
				(gr_poly
					(pts
						(arc
							(start 0.3048 -0.2032)
							(mid 0.275042 -0.275042)
							(end 0.2032 -0.3048)
						)
						(arc
							(start -0.2032 -0.3048)
							(mid -0.275042 -0.275042)
							(end -0.3048 -0.2032)
						)
						(arc
							(start -0.3048 0.2032)
							(mid -0.275042 0.275042)
							(end -0.2032 0.3048)
						)
						(arc
							(start 0.2032 0.3048)
							(mid 0.275042 0.275042)
							(end 0.3048 0.2032)
						)
					)
					(width 0)
					(fill yes)
				)
			)
		)
	)
	(footprint ""
		(layer "F.Cu")
		(at 263.271 -65.532)
		(property "Reference" "C308"
			(at 0 0 0)
			(layer "F.SilkS")
			(hide yes)
			(effects
				(font
					(size 1.27 1.27)
				)
			)
		)
		(property "Value" "SC22U25V5MX-GP"
			(at -0.0762 -6.1214 0)
			(unlocked yes)
			(layer "F.Fab")
			(hide yes)
			(effects
				(font
					(size 1.016 1.016)
					(thickness 0.1524)
				)
			)
		)
		(property "Device Type" "C805H58"
			(at -0.0762 -8.1534 0)
			(unlocked yes)
			(layer "F.Fab")
			(hide yes)
			(effects
				(font
					(size 1.016 1.016)
					(thickness 0.1524)
				)
			)
		)
		(duplicate_pad_numbers_are_jumpers no)
		(fp_line
			(start 0.635 0)
			(end -0.635 0)
			(stroke
				(width 0.508)
				(type default)
			)
			(layer "F.SilkS")
		)
		(fp_rect
			(start -0.9652 1.778)
			(end 0.9652 -1.778)
			(stroke
				(width 0)
				(type default)
			)
			(fill no)
			(layer "F.CrtYd")
		)
		(fp_poly
			(pts
				(xy -0.9652 -1.778) (xy 0.9652 -1.778) (xy 0.9652 1.778) (xy -0.9652 1.778)
			)
			(stroke
				(width 0)
				(type default)
			)
			(fill no)
			(layer "F.Fab")
		)
		(pad "1" smd rect
			(at 0 -0.9652)
			(size 1.397 1.143)
			(layers "F.Cu" "F.Mask" "F.Paste")
			(net "P12V_MSB")
		)
		(pad "2" smd rect
			(at 0 0.9652)
			(size 1.397 1.143)
			(layers "F.Cu" "F.Mask" "F.Paste")
			(net "GND")
		)
	)
)
